(kicad_pcb
	(version 20260206)
	(generator "pcbnew")
	(generator_version "10.0")
	(general
		(thickness 1.6)
		(legacy_teardrops no)
	)
	(paper "A4")
	(title_block
		(title "Bryce Canyon_F.DPB_16315-1-OCP.brd")
		(comment 1 "Bryce Canyon / footprints 959-964 of 2223")
	)
	(layers
		(0 "F.Cu" signal "TOP")
		(4 "In1.Cu" signal "L2GND")
		(6 "In2.Cu" signal "L3")
		(8 "In3.Cu" signal "L4GND")
		(10 "In4.Cu" signal "L5")
		(12 "In5.Cu" signal "L6VCC")
		(14 "In6.Cu" signal "L7VCC")
		(16 "In7.Cu" signal "L8")
		(18 "In8.Cu" signal "L9GND")
		(20 "In9.Cu" signal "L10")
		(22 "In10.Cu" signal "L11GND")
		(2 "B.Cu" signal "BOTTOM")
		(9 "F.Adhes" user "F.Adhesive")
		(11 "B.Adhes" user "B.Adhesive")
		(13 "F.Paste" user "Package Geometry/Pastemask Top")
		(15 "B.Paste" user "Package Geometry/Pastemask Bottom")
		(5 "F.SilkS" user "Ref Des/Silkscreen Top")
		(7 "B.SilkS" user "Ref Des/Silkscreen Bottom")
		(1 "F.Mask" user "Board Geometry/Soldermask Top")
		(3 "B.Mask" user "Board Geometry/Soldermask Bottom")
		(17 "Dwgs.User" user "User.Drawings")
		(19 "Cmts.User" user "User.Comments")
		(21 "Eco1.User" user "User.Eco1")
		(23 "Eco2.User" user "User.Eco2")
		(25 "Edge.Cuts" user "Board Geometry/Outline")
		(27 "Margin" user)
		(31 "F.CrtYd" user "Package Geometry/Place Bound Top")
		(29 "B.CrtYd" user "Package Geometry/Place Bound Bottom")
		(35 "F.Fab" user "Ref Des/Assembly Top")
		(33 "B.Fab" user "Ref Des/Assembly Bottom")
	)
	(footprint ""
		(layer "F.Cu")
		(at 393.90955 -288.638742 90)
		(property "Reference" "C152"
			(at 0 0 90)
			(layer "F.SilkS")
			(hide yes)
			(effects
				(font
					(size 1.27 1.27)
				)
			)
		)
		(property "Value" "SCD033U25V2KX-GP"
			(at 1.1811 -2.7051 90)
			(unlocked yes)
			(layer "F.Fab")
			(hide yes)
			(effects
				(font
					(size 1.016 1.016)
					(thickness 0.1524)
				)
			)
		)
		(property "Device Type" "C402H22"
			(at 1.1811 -4.2291 90)
			(unlocked yes)
			(layer "F.Fab")
			(hide yes)
			(effects
				(font
					(size 1.016 1.016)
					(thickness 0.1524)
				)
			)
		)
		(duplicate_pad_numbers_are_jumpers no)
		(fp_rect
			(start -0.4318 0.9525)
			(end 0.4318 -0.9525)
			(stroke
				(width 0)
				(type default)
			)
			(fill no)
			(layer "F.CrtYd")
		)
		(fp_rect
			(start -0.4318 0.9525)
			(end 0.4318 -0.9525)
			(stroke
				(width 0)
				(type default)
			)
			(fill no)
			(layer "F.Fab")
		)
		(pad "1" smd custom
			(at 0 -0.4445 90)
			(size 0.1524 0.1524)
			(layers "F.Cu" "F.Mask" "F.Paste")
			(net "SW_HDD_P8")
			(options
				(clearance outline)
				(anchor circle)
			)
			(primitives
				(gr_poly
					(pts
						(arc
							(start 0.3048 -0.2032)
							(mid 0.275042 -0.275042)
							(end 0.2032 -0.3048)
						)
						(arc
							(start -0.2032 -0.3048)
							(mid -0.275042 -0.275042)
							(end -0.3048 -0.2032)
						)
						(arc
							(start -0.3048 0.2032)
							(mid -0.275042 0.275042)
							(end -0.2032 0.3048)
						)
						(arc
							(start 0.2032 0.3048)
							(mid 0.275042 0.275042)
							(end 0.3048 0.2032)
						)
					)
					(width 0)
					(fill yes)
				)
			)
		)
		(pad "2" smd custom
			(at 0 0.4445 90)
			(size 0.1524 0.1524)
			(layers "F.Cu" "F.Mask" "F.Paste")
			(net "GND")
			(options
				(clearance outline)
				(anchor circle)
			)
			(primitives
				(gr_poly
					(pts
						(arc
							(start 0.3048 -0.2032)
							(mid 0.275042 -0.275042)
							(end 0.2032 -0.3048)
						)
						(arc
							(start -0.2032 -0.3048)
							(mid -0.275042 -0.275042)
							(end -0.3048 -0.2032)
						)
						(arc
							(start -0.3048 0.2032)
							(mid -0.275042 0.275042)
							(end -0.2032 0.3048)
						)
						(arc
							(start 0.2032 0.3048)
							(mid 0.275042 0.275042)
							(end 0.3048 0.2032)
						)
					)
					(width 0)
					(fill yes)
				)
			)
		)
	)
	(footprint ""
		(layer "F.Cu")
		(at 265.1506 -230.3018)
		(property "Reference" "R97"
			(at 0 0 0)
			(layer "F.SilkS")
			(hide yes)
			(effects
				(font
					(size 1.27 1.27)
				)
			)
		)
		(property "Value" "4K7R2F-GP"
			(at 0.064008 -3.993896 0)
			(unlocked yes)
			(layer "F.Fab")
			(hide yes)
			(effects
				(font
					(size 1.016 1.016)
					(thickness 0.1524)
				)
			)
		)
		(property "Device Type" "R402H16"
			(at 0.064008 -5.517896 0)
			(unlocked yes)
			(layer "F.Fab")
			(hide yes)
			(effects
				(font
					(size 1.016 1.016)
					(thickness 0.1524)
				)
			)
		)
		(duplicate_pad_numbers_are_jumpers no)
		(fp_line
			(start -0.508 -0.9398)
			(end -0.508 0.9398)
			(stroke
				(width 0.1524)
				(type default)
			)
			(layer "F.SilkS")
		)
		(fp_line
			(start 0.508 -0.9398)
			(end -0.508 -0.9398)
			(stroke
				(width 0.1524)
				(type default)
			)
			(layer "F.SilkS")
		)
		(fp_rect
			(start -0.508 0.9398)
			(end 0.508 -0.9398)
			(stroke
				(width 0)
				(type default)
			)
			(fill no)
			(layer "F.CrtYd")
		)
		(fp_rect
			(start -0.508 0.9398)
			(end 0.508 -0.9398)
			(stroke
				(width 0)
				(type default)
			)
			(fill no)
			(layer "F.Fab")
		)
		(pad "1" smd custom
			(at 0 -0.4445)
			(size 0.1397 0.1397)
			(layers "F.Cu" "F.Mask" "F.Paste")
			(net "IO_EXP3_A1")
			(options
				(clearance outline)
				(anchor circle)
			)
			(primitives
				(gr_poly
					(pts
						(arc
							(start -0.1778 -0.2794)
							(mid -0.249642 -0.249642)
							(end -0.2794 -0.1778)
						)
						(arc
							(start -0.2794 0.1778)
							(mid -0.249642 0.249642)
							(end -0.1778 0.2794)
						)
						(arc
							(start 0.1778 0.2794)
							(mid 0.249642 0.249642)
							(end 0.2794 0.1778)
						)
						(arc
							(start 0.2794 -0.1778)
							(mid 0.249642 -0.249642)
							(end 0.1778 -0.2794)
						)
					)
					(width 0)
					(fill yes)
				)
			)
		)
		(pad "2" smd custom
			(at 0 0.4445)
			(size 0.1397 0.1397)
			(layers "F.Cu" "F.Mask" "F.Paste")
			(net "GND")
			(options
				(clearance outline)
				(anchor circle)
			)
			(primitives
				(gr_poly
					(pts
						(arc
							(start -0.1778 -0.2794)
							(mid -0.249642 -0.249642)
							(end -0.2794 -0.1778)
						)
						(arc
							(start -0.2794 0.1778)
							(mid -0.249642 0.249642)
							(end -0.1778 0.2794)
						)
						(arc
							(start 0.1778 0.2794)
							(mid 0.249642 0.249642)
							(end 0.2794 0.1778)
						)
						(arc
							(start 0.2794 -0.1778)
							(mid 0.249642 -0.249642)
							(end 0.1778 -0.2794)
						)
					)
					(width 0)
					(fill yes)
				)
			)
		)
	)
	(footprint ""
		(layer "F.Cu")
		(at 384.734562 -44.219368 -90)
		(property "Reference" "C454"
			(at 0 0 270)
			(layer "F.SilkS")
			(hide yes)
			(effects
				(font
					(size 1.27 1.27)
				)
			)
		)
		(property "Value" "SCD01U16V1KX-GP"
			(at -2.8321 -1.7399 270)
			(unlocked yes)
			(layer "F.Fab")
			(hide yes)
			(effects
				(font
					(size 1.016 1.016)
					(thickness 0.1524)
				)
			)
		)
		(property "Device Type" "C0201H13"
			(at -2.8321 -3.2639 270)
			(unlocked yes)
			(layer "F.Fab")
			(hide yes)
			(effects
				(font
					(size 1.016 1.016)
					(thickness 0.1524)
				)
			)
		)
		(duplicate_pad_numbers_are_jumpers no)
		(fp_rect
			(start -0.2794 0.6477)
			(end 0.2794 -0.6477)
			(stroke
				(width 0)
				(type default)
			)
			(fill no)
			(layer "F.CrtYd")
		)
		(fp_rect
			(start -0.2794 0.6477)
			(end 0.2794 -0.6477)
			(stroke
				(width 0)
				(type default)
			)
			(fill no)
			(layer "F.Fab")
		)
		(pad "1" smd custom
			(at 0 -0.2794 270)
			(size 0.0762 0.0762)
			(layers "F.Cu" "F.Mask" "F.Paste")
			(net "SAS_HDD_RX_N32")
			(options
				(clearance outline)
				(anchor circle)
			)
			(primitives
				(gr_poly
					(pts
						(arc
							(start 0.1524 -0.127)
							(mid 0.137521 -0.162921)
							(end 0.1016 -0.1778)
						)
						(arc
							(start -0.1016 -0.1778)
							(mid -0.137521 -0.162921)
							(end -0.1524 -0.127)
						)
						(arc
							(start -0.1524 0.127)
							(mid -0.137521 0.162921)
							(end -0.1016 0.1778)
						)
						(arc
							(start 0.1016 0.1778)
							(mid 0.137521 0.162921)
							(end 0.1524 0.127)
						)
					)
					(width 0)
					(fill yes)
				)
			)
		)
		(pad "2" smd custom
			(at 0 0.2794 270)
			(size 0.0762 0.0762)
			(layers "F.Cu" "F.Mask" "F.Paste")
			(net "PHY_SCC_A_TO_DRV_A_32_DN")
			(options
				(clearance outline)
				(anchor circle)
			)
			(primitives
				(gr_poly
					(pts
						(arc
							(start 0.1524 -0.127)
							(mid 0.137521 -0.162921)
							(end 0.1016 -0.1778)
						)
						(arc
							(start -0.1016 -0.1778)
							(mid -0.137521 -0.162921)
							(end -0.1524 -0.127)
						)
						(arc
							(start -0.1524 0.127)
							(mid -0.137521 0.162921)
							(end -0.1016 0.1778)
						)
						(arc
							(start 0.1016 0.1778)
							(mid 0.137521 0.162921)
							(end 0.1524 0.127)
						)
					)
					(width 0)
					(fill yes)
				)
			)
		)
	)
	(footprint ""
		(layer "F.Cu")
		(at 444.4238 -295.0972 -90)
		(property "Reference" "R364"
			(at 0 0 270)
			(layer "F.SilkS")
			(hide yes)
			(effects
				(font
					(size 1.27 1.27)
				)
			)
		)
		(property "Value" "220R3F-1-GP"
			(at -0.0254 -2.5146 270)
			(unlocked yes)
			(layer "F.Fab")
			(hide yes)
			(effects
				(font
					(size 1.016 1.016)
					(thickness 0.1524)
				)
			)
		)
		(property "Device Type" "R603H22"
			(at -0.0254 -4.0386 270)
			(unlocked yes)
			(layer "F.Fab")
			(hide yes)
			(effects
				(font
					(size 1.016 1.016)
					(thickness 0.1524)
				)
			)
		)
		(duplicate_pad_numbers_are_jumpers no)
		(fp_line
			(start -0.4826 0)
			(end -0.2032 0)
			(stroke
				(width 0.2032)
				(type default)
			)
			(layer "F.SilkS")
		)
		(fp_line
			(start 0.2032 0)
			(end 0.4826 0)
			(stroke
				(width 0.2032)
				(type default)
			)
			(layer "F.SilkS")
		)
		(fp_rect
			(start -0.5842 1.3335)
			(end 0.5842 -1.3335)
			(stroke
				(width 0)
				(type default)
			)
			(fill no)
			(layer "F.CrtYd")
		)
		(fp_rect
			(start -0.5842 1.3335)
			(end 0.5842 -1.3335)
			(stroke
				(width 0)
				(type default)
			)
			(fill no)
			(layer "F.Fab")
		)
		(pad "1" smd custom
			(at 0 -0.762 270)
			(size 0.2159 0.2159)
			(layers "F.Cu" "F.Mask" "F.Paste")
			(net "HDD_PRSNT_10")
			(options
				(clearance outline)
				(anchor circle)
			)
			(primitives
				(gr_poly
					(pts
						(arc
							(start -0.3302 -0.4318)
							(mid -0.402042 -0.402042)
							(end -0.4318 -0.3302)
						)
						(arc
							(start -0.4318 0.3302)
							(mid -0.402042 0.402042)
							(end -0.3302 0.4318)
						)
						(arc
							(start 0.3302 0.4318)
							(mid 0.402042 0.402042)
							(end 0.4318 0.3302)
						)
						(arc
							(start 0.4318 -0.3302)
							(mid 0.402042 -0.402042)
							(end 0.3302 -0.4318)
						)
					)
					(width 0)
					(fill yes)
				)
			)
		)
		(pad "2" smd custom
			(at 0 0.762 270)
			(size 0.2159 0.2159)
			(layers "F.Cu" "F.Mask" "F.Paste")
			(net "DRIVE_A_10_INS")
			(options
				(clearance outline)
				(anchor circle)
			)
			(primitives
				(gr_poly
					(pts
						(arc
							(start -0.3302 -0.4318)
							(mid -0.402042 -0.402042)
							(end -0.4318 -0.3302)
						)
						(arc
							(start -0.4318 0.3302)
							(mid -0.402042 0.402042)
							(end -0.3302 0.4318)
						)
						(arc
							(start 0.3302 0.4318)
							(mid 0.402042 0.402042)
							(end 0.4318 0.3302)
						)
						(arc
							(start 0.4318 -0.3302)
							(mid 0.402042 -0.402042)
							(end 0.3302 -0.4318)
						)
					)
					(width 0)
					(fill yes)
				)
			)
		)
	)
	(footprint ""
		(layer "F.Cu")
		(at 469.942926 -59.857894)
		(property "Reference" "Q212"
			(at 0 0 0)
			(layer "F.SilkS")
			(hide yes)
			(effects
				(font
					(size 1.27 1.27)
				)
			)
		)
		(property "Value" "AO4407AL-GP"
			(at -3.707384 -1.5367 0)
			(unlocked yes)
			(layer "F.Fab")
			(hide yes)
			(effects
				(font
					(size 1.016 1.016)
					(thickness 0.1524)
				)
			)
		)
		(property "Device Type" "SOIC8H69"
			(at -3.707384 -3.0607 0)
			(unlocked yes)
			(layer "F.Fab")
			(hide yes)
			(effects
				(font
					(size 1.016 1.016)
					(thickness 0.1524)
				)
			)
		)
		(duplicate_pad_numbers_are_jumpers no)
		(fp_line
			(start -2.7432 -1.4224)
			(end -2.7432 1.4224)
			(stroke
				(width 0.1524)
				(type default)
			)
			(layer "F.SilkS")
		)
		(fp_line
			(start -2.7432 1.4224)
			(end -2.6416 1.4224)
			(stroke
				(width 0.1524)
				(type default)
			)
			(layer "F.SilkS")
		)
		(fp_line
			(start -2.7432 1.4224)
			(end 2.1336 1.4224)
			(stroke
				(width 0.1524)
				(type default)
			)
			(layer "F.SilkS")
		)
		(fp_line
			(start -2.7178 -0.508)
			(end -2.1844 -0.0508)
			(stroke
				(width 0.1524)
				(type default)
			)
			(layer "F.SilkS")
		)
		(fp_line
			(start -2.6289 3.4417)
			(end -2.6289 1.4732)
			(stroke
				(width 0.381)
				(type default)
			)
			(layer "F.SilkS")
		)
		(fp_line
			(start -2.1844 -0.0508)
			(end -2.7178 0.508)
			(stroke
				(width 0.1524)
				(type default)
			)
			(layer "F.SilkS")
		)
		(fp_line
			(start 2.1336 -1.4224)
			(end -2.7432 -1.4224)
			(stroke
				(width 0.1524)
				(type default)
			)
			(layer "F.SilkS")
		)
		(fp_line
			(start 2.1336 1.4224)
			(end 2.1336 -1.4224)
			(stroke
				(width 0.1524)
				(type default)
			)
			(layer "F.SilkS")
		)
		(fp_poly
			(pts
				(xy -2.2098 -1.4224) (xy -2.2098 1.4224) (xy 2.2098 1.4224) (xy 2.2098 -1.4224)
			)
			(stroke
				(width 0)
				(type default)
			)
			(fill yes)
			(layer "F.SilkS")
		)
		(fp_rect
			(start -2.450084 2.999994)
			(end 2.450084 -2.999994)
			(stroke
				(width 0)
				(type default)
			)
			(fill no)
			(layer "F.CrtYd")
		)
		(fp_poly
			(pts
				(xy -2.8194 3.6322) (xy -2.8194 -3.6322) (xy 2.8194 -3.6322) (xy 2.8194 1.18364) (xy 2.450084 1.18364)
				(xy 2.450084 -2.999994) (xy -2.450084 -2.999994) (xy -2.450084 2.999994) (xy 2.450084 2.999994)
				(xy 2.450084 1.18618) (xy 2.8194 1.18618) (xy 2.8194 3.6322)
			)
			(stroke
				(width 0)
				(type default)
			)
			(fill no)
			(layer "F.CrtYd")
		)
		(fp_rect
			(start -2.8194 3.6322)
			(end 2.8194 -3.6322)
			(stroke
				(width 0)
				(type default)
			)
			(fill no)
			(layer "F.Fab")
		)
		(pad "1" smd rect
			(at -1.905 2.54)
			(size 0.635 1.651)
			(layers "F.Cu" "F.Mask" "F.Paste")
			(net "P12V_A")
		)
		(pad "2" smd rect
			(at -0.635 2.54)
			(size 0.635 1.651)
			(layers "F.Cu" "F.Mask" "F.Paste")
			(net "P12V_A")
		)
		(pad "3" smd rect
			(at 0.635 2.54)
			(size 0.635 1.651)
			(layers "F.Cu" "F.Mask" "F.Paste")
			(net "P12V_A")
		)
		(pad "4" smd rect
			(at 1.905 2.54)
			(size 0.635 1.651)
			(layers "F.Cu" "F.Mask" "F.Paste")
			(net "SW_HDD_N35")
		)
		(pad "5" smd rect
			(at 1.905 -2.54)
			(size 0.635 1.651)
			(layers "F.Cu" "F.Mask" "F.Paste")
			(net "P12V_HDD35")
		)
		(pad "6" smd rect
			(at 0.635 -2.54)
			(size 0.635 1.651)
			(layers "F.Cu" "F.Mask" "F.Paste")
			(net "P12V_HDD35")
		)
		(pad "7" smd rect
			(at -0.635 -2.54)
			(size 0.635 1.651)
			(layers "F.Cu" "F.Mask" "F.Paste")
			(net "P12V_HDD35")
		)
		(pad "8" smd rect
			(at -1.905 -2.54)
			(size 0.635 1.651)
			(layers "F.Cu" "F.Mask" "F.Paste")
			(net "P12V_HDD35")
		)
	)
	(footprint ""
		(layer "F.Cu")
		(at 14.842998 -283.482542 -90)
		(property "Reference" "R973"
			(at 0 0 270)
			(layer "F.SilkS")
			(hide yes)
			(effects
				(font
					(size 1.27 1.27)
				)
			)
		)
		(property "Value" "300KR2F-GP"
			(at 0.064008 -3.993896 270)
			(unlocked yes)
			(layer "F.Fab")
			(hide yes)
			(effects
				(font
					(size 1.016 1.016)
					(thickness 0.1524)
				)
			)
		)
		(property "Device Type" "R402H16"
			(at 0.064008 -5.517896 270)
			(unlocked yes)
			(layer "F.Fab")
			(hide yes)
			(effects
				(font
					(size 1.016 1.016)
					(thickness 0.1524)
				)
			)
		)
		(duplicate_pad_numbers_are_jumpers no)
		(fp_line
			(start -0.508 -0.9398)
			(end -0.508 0.9398)
			(stroke
				(width 0.1524)
				(type default)
			)
			(layer "F.SilkS")
		)
		(fp_line
			(start 0.508 -0.9398)
			(end -0.508 -0.9398)
			(stroke
				(width 0.1524)
				(type default)
			)
			(layer "F.SilkS")
		)
		(fp_rect
			(start -0.508 0.9398)
			(end 0.508 -0.9398)
			(stroke
				(width 0)
				(type default)
			)
			(fill no)
			(layer "F.CrtYd")
		)
		(fp_rect
			(start -0.508 0.9398)
			(end 0.508 -0.9398)
			(stroke
				(width 0)
				(type default)
			)
			(fill no)
			(layer "F.Fab")
		)
		(pad "1" smd custom
			(at 0 -0.4445 270)
			(size 0.1397 0.1397)
			(layers "F.Cu" "F.Mask" "F.Paste")
			(net "SW_HDD_N0")
			(options
				(clearance outline)
				(anchor circle)
			)
			(primitives
				(gr_poly
					(pts
						(arc
							(start -0.1778 -0.2794)
							(mid -0.249642 -0.249642)
							(end -0.2794 -0.1778)
						)
						(arc
							(start -0.2794 0.1778)
							(mid -0.249642 0.249642)
							(end -0.1778 0.2794)
						)
						(arc
							(start 0.1778 0.2794)
							(mid 0.249642 0.249642)
							(end 0.2794 0.1778)
						)
						(arc
							(start 0.2794 -0.1778)
							(mid 0.249642 -0.249642)
							(end 0.1778 -0.2794)
						)
					)
					(width 0)
					(fill yes)
				)
			)
		)
		(pad "2" smd custom
			(at 0 0.4445 270)
			(size 0.1397 0.1397)
			(layers "F.Cu" "F.Mask" "F.Paste")
			(net "P12V_A")
			(options
				(clearance outline)
				(anchor circle)
			)
			(primitives
				(gr_poly
					(pts
						(arc
							(start -0.1778 -0.2794)
							(mid -0.249642 -0.249642)
							(end -0.2794 -0.1778)
						)
						(arc
							(start -0.2794 0.1778)
							(mid -0.249642 0.249642)
							(end -0.1778 0.2794)
						)
						(arc
							(start 0.1778 0.2794)
							(mid 0.249642 0.249642)
							(end 0.2794 0.1778)
						)
						(arc
							(start 0.2794 -0.1778)
							(mid 0.249642 -0.249642)
							(end 0.1778 -0.2794)
						)
					)
					(width 0)
					(fill yes)
				)
			)
		)
	)
)
